(kicad_pcb
	(version 20221018)
	(generator pcbnew)
	(general
    (thickness 0.908)
  )
	(paper "A4")
	(title_block
    (title "HDMI-MIPI Bridge")
    (date "2024-04-24")
    (rev "1.3.2")
		(comment 9 "footprints 107-112 of 121")
	)
	(layers
    (0 "F.Cu" signal)
    (1 "In1.Cu" signal)
    (2 "In2.Cu" signal)
    (31 "B.Cu" signal)
    (32 "B.Adhes" user "B.Adhesive")
    (33 "F.Adhes" user "F.Adhesive")
    (34 "B.Paste" user)
    (35 "F.Paste" user)
    (36 "B.SilkS" user "B.Silkscreen")
    (37 "F.SilkS" user "F.Silkscreen")
    (38 "B.Mask" user)
    (39 "F.Mask" user)
    (40 "Dwgs.User" user "User.Drawings")
    (41 "Cmts.User" user "User.Comments")
    (42 "Eco1.User" user "User.Eco1")
    (43 "Eco2.User" user "User.Eco2")
    (44 "Edge.Cuts" user)
    (45 "Margin" user)
    (46 "B.CrtYd" user "B.Courtyard")
    (47 "F.CrtYd" user "F.Courtyard")
    (48 "B.Fab" user)
    (49 "F.Fab" user)
  )
	(footprint "antmicro-footprints:C_0402_1005Metric" (layer "B.Cu")
    (at 139.8 109.1 180)
    (descr "Capacitor SMD 0402")
    (tags "capacitor SMD 0402")
    (property "Author" "Antmicro")
    (property "Dielectric" "X5R")
    (property "License" "Apache-2.0")
    (property "MPN" "GRM155R61H104KE14D")
    (property "Manufacturer" "Murata")
    (property "Public" "False")
    (property "Sheetfile" "channel1.kicad_sch")
    (property "Sheetname" "Channel 1")
    (property "Val" "100n")
    (property "Voltage" "50V")
    (property "ki_description" "SMD Multilayer Ceramic Capacitor, 0.1 µF, 50 V, 0402 [1005 Metric], ± 10%, X5R, GRM Series")
    (property "ki_keywords" "0402, SMT, CAPACITOR, PASSIVE, CERAMIC, MLCC")
    (attr smd)
    (fp_text reference "C2" (at 1.02 -0.25) (layer "B.SilkS")
        (effects (font (size 0.65 0.65) (thickness 0.13)) (justify left bottom mirror))
    )
    (fp_text value "C_100n_0402" (at 0 -1.4) (layer "B.Fab")
        (effects (font (size 0.65 0.65) (thickness 0.13)) (justify left bottom mirror))
    )
    (fp_text user "Author: Antmicro" (at -0.932 -4.17) (layer "B.Fab") hide
        (effects (font (size 0.7 0.7) (thickness 0.15)) (justify left bottom mirror))
    )
    (fp_text user "${REFERENCE}" (at -0.932 -3.168) (layer "B.Fab") hide
        (effects (font (size 0.7 0.7) (thickness 0.15)) (justify left bottom mirror))
    )
    (fp_text user "License: Apache-2.0" (at -0.932 -5.17) (layer "B.Fab") hide
        (effects (font (size 0.7 0.7) (thickness 0.15)) (justify left bottom mirror))
    )
    (fp_rect (start -0.925 0.47) (end 0.925 -0.47)
      (stroke (width 0.05) (type default)) (fill none) (layer "B.CrtYd"))
    (fp_line (start -0.494 -0.248) (end -0.494 0.25)
      (stroke (width 0.15) (type solid)) (layer "B.Fab"))
    (fp_line (start -0.494 0.25) (end 0.504 0.25)
      (stroke (width 0.15) (type solid)) (layer "B.Fab"))
    (fp_line (start 0.504 -0.248) (end -0.494 -0.248)
      (stroke (width 0.15) (type solid)) (layer "B.Fab"))
    (fp_line (start 0.504 0.25) (end 0.504 -0.248)
      (stroke (width 0.15) (type solid)) (layer "B.Fab"))
    (pad "1" smd roundrect (at -0.48 0 180) (size 0.59 0.64) (layers "B.Cu" "B.Paste" "B.Mask") (roundrect_rratio 0.25)
      (net 2 "GND") (pintype "passive"))
    (pad "2" smd roundrect (at 0.48 0 180) (size 0.59 0.64) (layers "B.Cu" "B.Paste" "B.Mask") (roundrect_rratio 0.25)
      (net 3 "Net-(U1C-DAOUT)") (pintype "passive"))
  )
	(footprint "antmicro-footprints:R_0402_1005Metric" (layer "B.Cu")
    (at 155.1 112.25 180)
    (descr "Resistor SMD 0402")
    (tags "resistor SMD 0402")
    (property "Author" "Antmicro")
    (property "License" "Apache-2.0")
    (property "MPN" "CR0402-FX-1002GLF")
    (property "Manufacturer" "Bourns")
    (property "Public" "False")
    (property "Sheetfile" "channel2.kicad_sch")
    (property "Sheetname" "Channel 2")
    (property "Tolerance" "1%")
    (property "Val" "10k")
    (property "ki_description" "SMD Chip Resistor, 10 kohm, ± 1%, 62.5 mW, 0402 [1005 Metric], Thick Film, General Purpose")
    (property "ki_keywords" "0402, SMT, RESISTOR, PASSIVE")
    (attr smd)
    (fp_text reference "R16" (at 0.8 -0.35) (layer "B.SilkS")
        (effects (font (size 0.65 0.65) (thickness 0.13)) (justify left bottom mirror))
    )
    (fp_text value "R_10k_0402" (at 0 -1.4) (layer "B.Fab")
        (effects (font (size 0.65 0.65) (thickness 0.13)) (justify left bottom mirror))
    )
    (fp_text user "${REFERENCE}" (at -0.95 -3.168) (layer "B.Fab") hide
        (effects (font (size 0.7 0.7) (thickness 0.15)) (justify left bottom mirror))
    )
    (fp_text user "Author: Antmicro" (at -0.95 -4.169) (layer "B.Fab") hide
        (effects (font (size 0.7 0.7) (thickness 0.15)) (justify left bottom mirror))
    )
    (fp_text user "License: Apache-2.0" (at -0.95 -5.169) (layer "B.Fab") hide
        (effects (font (size 0.7 0.7) (thickness 0.15)) (justify left bottom mirror))
    )
    (fp_rect (start -0.925 0.47) (end 0.925 -0.47)
      (stroke (width 0.05) (type default)) (fill none) (layer "B.CrtYd"))
    (fp_rect (start -0.5 0.25) (end 0.5 -0.25)
      (stroke (width 0.15) (type solid)) (fill none) (layer "B.Fab"))
    (pad "1" smd roundrect (at -0.48 0 180) (size 0.59 0.64) (layers "B.Cu" "B.Paste" "B.Mask") (roundrect_rratio 0.25)
      (net 107 "/Channel 2/CH2_~{RST}") (pintype "passive"))
    (pad "2" smd roundrect (at 0.48 0 180) (size 0.59 0.64) (layers "B.Cu" "B.Paste" "B.Mask") (roundrect_rratio 0.25)
      (net 9 "+3V3") (pintype "passive"))
  )
	(footprint "antmicro-footprints:Spacer_Drill3.7mm_H6mm_9774060151R" (layer "B.Cu")
    (at 179 131 180)
    (property "Author" "Antmicro")
    (property "License" "Apache-2.0")
    (property "MPN" "9774060151R")
    (property "Manufacturer" "Würth Elektronik")
    (property "Public" "False")
    (property "Sheetfile" "csi.kicad_sch")
    (property "Sheetname" "CSI")
    (property "ki_description" "Spacer, SMT, Non Stop, Steel, Swage Round, 5.1 mm x 6 mm, M2.5 Thread, WA-SMSI Series")
    (property "ki_keywords" "MECHANICAL, SPACER")
    (attr smd)
    (fp_text reference "SP3" (at 0 3.2) (layer "B.SilkS") hide
        (effects (font (size 0.7 0.7) (thickness 0.15)) (justify left bottom mirror))
    )
    (fp_text value "Spacer_Drill3.7mm_H6mm_9774060151R" (at 0 -4) (layer "B.Fab")
        (effects (font (size 0.7 0.7) (thickness 0.15)) (justify left bottom mirror))
    )
    (fp_text user "${REFERENCE}" (at -2.551 -5.25) (layer "B.Fab") hide
        (effects (font (size 0.7 0.7) (thickness 0.15)) (justify left bottom mirror))
    )
    (fp_text user "License: Apache-2.0" (at -2.551 -7.75) (layer "B.Fab") hide
        (effects (font (size 0.7 0.7) (thickness 0.15)) (justify left bottom mirror))
    )
    (fp_text user "Author: Antmicro" (at -2.551 -6.5) (layer "B.Fab") hide
        (effects (font (size 0.7 0.7) (thickness 0.15)) (justify left bottom mirror))
    )
    (fp_circle (center 0 0) (end 3.05 0)
      (stroke (width 0.05) (type solid)) (fill none) (layer "B.CrtYd"))
    (fp_circle (center -0.001 0) (end 2.548 0)
      (stroke (width 0.15) (type solid)) (fill none) (layer "B.Fab"))
    (pad "" smd custom (at -1.71 -1.699 90) (size 0.62 0.62) (layers "B.Paste")
      (thermal_bridge_angle 90)
      (options (clearance outline) (anchor circle))
      (primitives
        (gr_arc (start 1.266786 0.24747) (mid 0.285453 -0.29439) (end -0.250195 -1.279127) (width 0.2))
        (gr_arc (start 1.259603 0.339191) (mid 0.218448 -0.232561) (end -0.34334 -1.279127) (width 0.2))
        (gr_arc (start 1.255279 0.431435) (mid 0.152481 -0.169693) (end -0.436309 -1.279127) (width 0.2))
        (gr_arc (start 1.253811 0.524161) (mid 0.087542 -0.105784) (end -0.529126 -1.279127) (width 0.2))
        (gr_arc (start 1.275473 0.621136) (mid 0.0309 -0.033527) (end -0.621807 -1.279127) (width 0.2))
        (gr_arc (start 1.263664 0.711602) (mid -0.037759 0.026651) (end -0.71437 -1.279127) (width 0.2))
        (gr_arc (start 1.253435 0.802342) (mid -0.105837 0.087395) (end -0.806826 -1.279127) (width 0.2))
        (gr_arc (start 1.267475 0.897258) (mid -0.165236 0.156885) (end -0.899187 -1.279127) (width 0.2))
        (gr_arc (start 1.270645 0.990112) (mid -0.228522 0.222449) (end -0.991463 -1.279127) (width 0.2))
        (gr_arc (start 1.266278 1.081674) (mid -0.294507 0.285313) (end -1.083663 -1.279127) (width 0.2))
        (gr_line (start 1.279127 1.083663) (end 1.279127 0.250195) (width 0.2))
        (gr_line (start -1.083663 -1.279127) (end -0.250195 -1.279127) (width 0.2))
      ))
    (pad "" smd custom (at -1.71 1.71 180) (size 0.62 0.62) (layers "B.Paste")
      (thermal_bridge_angle 90)
      (options (clearance outline) (anchor circle))
      (primitives
        (gr_arc (start 1.266786 0.24747) (mid 0.285453 -0.29439) (end -0.250195 -1.279127) (width 0.2))
        (gr_arc (start 1.259603 0.339191) (mid 0.218448 -0.232561) (end -0.34334 -1.279127) (width 0.2))
        (gr_arc (start 1.255279 0.431435) (mid 0.152481 -0.169693) (end -0.436309 -1.279127) (width 0.2))
        (gr_arc (start 1.253811 0.524161) (mid 0.087542 -0.105784) (end -0.529126 -1.279127) (width 0.2))
        (gr_arc (start 1.275473 0.621136) (mid 0.0309 -0.033527) (end -0.621807 -1.279127) (width 0.2))
        (gr_arc (start 1.263664 0.711602) (mid -0.037759 0.026651) (end -0.71437 -1.279127) (width 0.2))
        (gr_arc (start 1.253435 0.802342) (mid -0.105837 0.087395) (end -0.806826 -1.279127) (width 0.2))
        (gr_arc (start 1.267475 0.897258) (mid -0.165236 0.156885) (end -0.899187 -1.279127) (width 0.2))
        (gr_arc (start 1.270645 0.990112) (mid -0.228522 0.222449) (end -0.991463 -1.279127) (width 0.2))
        (gr_arc (start 1.266278 1.081674) (mid -0.294507 0.285313) (end -1.083663 -1.279127) (width 0.2))
        (gr_line (start 1.279127 1.083663) (end 1.279127 0.250195) (width 0.2))
        (gr_line (start -1.083663 -1.279127) (end -0.250195 -1.279127) (width 0.2))
      ))
    (pad "" smd custom (at 1.699 -1.699) (size 0.62 0.62) (layers "B.Paste")
      (thermal_bridge_angle 90)
      (options (clearance outline) (anchor circle))
      (primitives
        (gr_arc (start 1.266786 0.24747) (mid 0.285453 -0.29439) (end -0.250195 -1.279127) (width 0.2))
        (gr_arc (start 1.259603 0.339191) (mid 0.218448 -0.232561) (end -0.34334 -1.279127) (width 0.2))
        (gr_arc (start 1.255279 0.431435) (mid 0.152481 -0.169693) (end -0.436309 -1.279127) (width 0.2))
        (gr_arc (start 1.253811 0.524161) (mid 0.087542 -0.105784) (end -0.529126 -1.279127) (width 0.2))
        (gr_arc (start 1.275473 0.621136) (mid 0.0309 -0.033527) (end -0.621807 -1.279127) (width 0.2))
        (gr_arc (start 1.263664 0.711602) (mid -0.037759 0.026651) (end -0.71437 -1.279127) (width 0.2))
        (gr_arc (start 1.253435 0.802342) (mid -0.105837 0.087395) (end -0.806826 -1.279127) (width 0.2))
        (gr_arc (start 1.267475 0.897258) (mid -0.165236 0.156885) (end -0.899187 -1.279127) (width 0.2))
        (gr_arc (start 1.270645 0.990112) (mid -0.228522 0.222449) (end -0.991463 -1.279127) (width 0.2))
        (gr_arc (start 1.266278 1.081674) (mid -0.294507 0.285313) (end -1.083663 -1.279127) (width 0.2))
        (gr_line (start 1.279127 1.083663) (end 1.279127 0.250195) (width 0.2))
        (gr_line (start -1.083663 -1.279127) (end -0.250195 -1.279127) (width 0.2))
      ))
    (pad "" smd custom (at 1.699 1.71 270) (size 0.62 0.62) (layers "B.Paste")
      (thermal_bridge_angle 90)
      (options (clearance outline) (anchor circle))
      (primitives
        (gr_arc (start 1.266786 0.24747) (mid 0.285453 -0.29439) (end -0.250195 -1.279127) (width 0.2))
        (gr_arc (start 1.259603 0.339191) (mid 0.218448 -0.232561) (end -0.34334 -1.279127) (width 0.2))
        (gr_arc (start 1.255279 0.431435) (mid 0.152481 -0.169693) (end -0.436309 -1.279127) (width 0.2))
        (gr_arc (start 1.253811 0.524161) (mid 0.087542 -0.105784) (end -0.529126 -1.279127) (width 0.2))
        (gr_arc (start 1.275473 0.621136) (mid 0.0309 -0.033527) (end -0.621807 -1.279127) (width 0.2))
        (gr_arc (start 1.263664 0.711602) (mid -0.037759 0.026651) (end -0.71437 -1.279127) (width 0.2))
        (gr_arc (start 1.253435 0.802342) (mid -0.105837 0.087395) (end -0.806826 -1.279127) (width 0.2))
        (gr_arc (start 1.267475 0.897258) (mid -0.165236 0.156885) (end -0.899187 -1.279127) (width 0.2))
        (gr_arc (start 1.270645 0.990112) (mid -0.228522 0.222449) (end -0.991463 -1.279127) (width 0.2))
        (gr_arc (start 1.266278 1.081674) (mid -0.294507 0.285313) (end -1.083663 -1.279127) (width 0.2))
        (gr_line (start 1.279127 1.083663) (end 1.279127 0.250195) (width 0.2))
        (gr_line (start -1.083663 -1.279127) (end -0.250195 -1.279127) (width 0.2))
      ))
    (pad "1" thru_hole circle (at -0.001 0 180) (size 6 6) (drill 3.7) (layers "*.Cu" "*.Mask")
      (net 2 "GND") (pintype "passive") (solder_paste_margin_ratio -0.05))
  )
	(footprint "antmicro-footprints:C_0402_1005Metric" (layer "B.Cu")
    (at 139.8 108.1 180)
    (descr "Capacitor SMD 0402")
    (tags "capacitor SMD 0402")
    (property "Author" "Antmicro")
    (property "Dielectric" "X5R")
    (property "License" "Apache-2.0")
    (property "MPN" "GRM155R61H104KE14D")
    (property "Manufacturer" "Murata")
    (property "Public" "False")
    (property "Sheetfile" "channel1.kicad_sch")
    (property "Sheetname" "Channel 1")
    (property "Val" "100n")
    (property "Voltage" "50V")
    (property "ki_description" "SMD Multilayer Ceramic Capacitor, 0.1 µF, 50 V, 0402 [1005 Metric], ± 10%, X5R, GRM Series")
    (property "ki_keywords" "0402, SMT, CAPACITOR, PASSIVE, CERAMIC, MLCC")
    (attr smd)
    (fp_text reference "C1" (at 1 -0.4) (layer "B.SilkS")
        (effects (font (size 0.65 0.65) (thickness 0.13)) (justify left bottom mirror))
    )
    (fp_text value "C_100n_0402" (at 0 -1.4) (layer "B.Fab")
        (effects (font (size 0.65 0.65) (thickness 0.13)) (justify left bottom mirror))
    )
    (fp_text user "${REFERENCE}" (at -0.932 -3.168) (layer "B.Fab") hide
        (effects (font (size 0.7 0.7) (thickness 0.15)) (justify left bottom mirror))
    )
    (fp_text user "License: Apache-2.0" (at -0.932 -5.17) (layer "B.Fab") hide
        (effects (font (size 0.7 0.7) (thickness 0.15)) (justify left bottom mirror))
    )
    (fp_text user "Author: Antmicro" (at -0.932 -4.17) (layer "B.Fab") hide
        (effects (font (size 0.7 0.7) (thickness 0.15)) (justify left bottom mirror))
    )
    (fp_rect (start -0.925 0.47) (end 0.925 -0.47)
      (stroke (width 0.05) (type default)) (fill none) (layer "B.CrtYd"))
    (fp_line (start -0.494 -0.248) (end -0.494 0.25)
      (stroke (width 0.15) (type solid)) (layer "B.Fab"))
    (fp_line (start -0.494 0.25) (end 0.504 0.25)
      (stroke (width 0.15) (type solid)) (layer "B.Fab"))
    (fp_line (start 0.504 -0.248) (end -0.494 -0.248)
      (stroke (width 0.15) (type solid)) (layer "B.Fab"))
    (fp_line (start 0.504 0.25) (end 0.504 -0.248)
      (stroke (width 0.15) (type solid)) (layer "B.Fab"))
    (pad "1" smd roundrect (at -0.48 0 180) (size 0.59 0.64) (layers "B.Cu" "B.Paste" "B.Mask") (roundrect_rratio 0.25)
      (net 2 "GND") (pintype "passive"))
    (pad "2" smd roundrect (at 0.48 0 180) (size 0.59 0.64) (layers "B.Cu" "B.Paste" "B.Mask") (roundrect_rratio 0.25)
      (net 1 "Net-(U1C-BIASDA)") (pintype "passive"))
  )
	(footprint "antmicro-footprints:TP_SMD_0.75mm" (layer "B.Cu")
    (at 154.3 103.1 180)
    (property "Author" "Antmicro")
    (property "License" "Apache-2.0")
    (property "MPN" "")
    (property "Manufacturer" "")
    (property "Public" "False")
    (property "Sheetfile" "channel2.kicad_sch")
    (property "Sheetname" "Channel 2")
    (property "exclude_from_bom" "")
    (property "ki_description" "SMT test point")
    (property "ki_keywords" "TESTPOINT")
    (attr exclude_from_pos_files exclude_from_bom)
    (fp_text reference "TP7" (at 0 0.6) (layer "B.SilkS")
        (effects (font (size 0.65 0.65) (thickness 0.13)) (justify left bottom mirror))
    )
    (fp_text value "TP_0.75mm_SMD" (at 0 -1.2) (layer "B.Fab")
        (effects (font (size 0.65 0.65) (thickness 0.13)) (justify left bottom mirror))
    )
    (fp_text user "${REFERENCE}" (at -0.4 -2.7) (layer "B.Fab") hide
        (effects (font (size 0.7 0.7) (thickness 0.15)) (justify left bottom mirror))
    )
    (fp_text user "Author: Antmicro" (at -0.4 -3.901) (layer "B.Fab") hide
        (effects (font (size 0.7 0.7) (thickness 0.15)) (justify left bottom mirror))
    )
    (fp_text user "License: Apache-2.0" (at -0.4 -5.101) (layer "B.Fab") hide
        (effects (font (size 0.7 0.7) (thickness 0.15)) (justify left bottom mirror))
    )
    (pad "1" smd circle (at 0 0 180) (size 0.75 0.75) (layers "B.Cu" "B.Mask")
      (net 119 "/Channel 2/HDMI2_HPDO") (pinfunction "1") (pintype "passive"))
  )
	(footprint "antmicro-footprints:R_0603_1608Metric" (layer "B.Cu")
    (at 130.7 113.6 180)
    (descr "Resistor SMD 0603")
    (tags "resistor SMD 0603")
    (property "Author" "Antmicro")
    (property "Current" "1A")
    (property "License" "Apache-2.0")
    (property "MPN" "CR0603-J/-000ELF")
    (property "Manufacturer" "Bourns")
    (property "Public" "False")
    (property "Sheetfile" "channel1.kicad_sch")
    (property "Sheetname" "Channel 1")
    (property "Tolerance" "")
    (property "Val" "0R")
    (property "ki_description" "Zero Ohm Resistor, Jumper, 0603 [1608 Metric], Thick Film, 100 mW, 1 A, Surface Mount Device, CR")
    (property "ki_keywords" "0603, SMT, RESISTOR, PASSIVE")
    (attr smd)
    (fp_text reference "R7" (at 1 -0.4) (layer "B.SilkS")
        (effects (font (size 0.7 0.7) (thickness 0.15)) (justify left bottom mirror))
    )
    (fp_text value "R_0R_0603" (at 0 -1.6) (layer "B.Fab")
        (effects (font (size 0.7 0.7) (thickness 0.15)) (justify left bottom mirror))
    )
    (fp_text user "Author: Antmicro" (at -1.25 -4.9) (layer "B.Fab") hide
        (effects (font (size 0.7 0.7) (thickness 0.15)) (justify left bottom mirror))
    )
    (fp_text user "License: Apache-2.0" (at -1.25 -5.9) (layer "B.Fab") hide
        (effects (font (size 0.7 0.7) (thickness 0.15)) (justify left bottom mirror))
    )
    (fp_text user "${REFERENCE}" (at -1.25 -3.898) (layer "B.Fab") hide
        (effects (font (size 0.7 0.7) (thickness 0.15)) (justify left bottom mirror))
    )
    (fp_line (start -0.15 -0.4) (end 0.15 -0.4)
      (stroke (width 0.15) (type solid)) (layer "B.SilkS"))
    (fp_line (start -0.15 0.4) (end 0.15 0.4)
      (stroke (width 0.15) (type solid)) (layer "B.SilkS"))
    (fp_rect (start -1.25 0.65) (end 1.25 -0.65)
      (stroke (width 0.05) (type solid)) (fill none) (layer "B.CrtYd"))
    (fp_rect (start -0.8 0.4) (end 0.8 -0.4)
      (stroke (width 0.15) (type solid)) (fill none) (layer "B.Fab"))
    (pad "1" smd roundrect (at -0.7 0 180) (size 0.8 1) (layers "B.Cu" "B.Paste" "B.Mask") (roundrect_rratio 0.2)
      (net 21 "Net-(U1B-VDDIO2)") (pintype "passive"))
    (pad "2" smd roundrect (at 0.7 0 180) (size 0.8 1) (layers "B.Cu" "B.Paste" "B.Mask") (roundrect_rratio 0.2)
      (net 9 "+3V3") (pintype "passive"))
  )
)
